M48
INCH,TZ
T01C.001
T02C.01
T03C.012
T04C.016
T05C.02
T06C.032
T07C.073
T08C.086
T09C.087
T010C.14
T011C.146
;EXTENTS: -109.478 -108.661 143.030 127.506 
;LEADER: 12 
;HEADER: 
;CODE  : ASCII 
;FILE  : 15669-1.rou for board 15669-1.brd
%
G90
F1
M16
T06
M16
G00X897455Y1801850
G40
M15
G01X901755
M16
G00X897455Y1975079
G40
M15
G01X901755
M16
G00X897455Y1396339
G40
M15
G01X901755
M16
G00X897455Y1569567
G40
M15
G01X901755
M16
G00X897455Y990827
G40
M15
G01X901755
M16
G00X897455Y1164055
G40
M15
G01X901755
M16
G00X897455Y585315
G40
M15
G01X901755
M16
G00X897455Y758543
G40
M15
G01X901755
M16
G00X897455Y179803
G40
M15
G01X901755
M16
G00X897455Y353031
G40
M15
G01X901755
M16
G00X169110Y1801850
G40
M15
G01X173410
M16
G00X169110Y1975079
G40
M15
G01X173410
M16
G00X169110Y1396339
G40
M15
G01X173410
M16
G00X169110Y1569567
G40
M15
G01X173410
M16
G00X169110Y990827
G40
M15
G01X173410
M16
G00X169110Y1164055
G40
M15
G01X173410
M16
G00X169110Y585315
G40
M15
G01X173410
M16
G00X169110Y758543
G40
M15
G01X173410
M16
G00X169110Y179803
G40
M15
G01X173410
M16
G00X169110Y353031
G40
M15
G01X173410
M16
G00X70685Y1812323
G40
M15
G01X74985
M16
G00X70685Y1639095
G40
M15
G01X74985
M16
G00X70685Y1406811
G40
M15
G01X74985
M16
G00X70685Y1233583
G40
M15
G01X74985
M16
G00X70685Y1001299
G40
M15
G01X74985
M16
G00X70685Y828070
G40
M15
G01X74985
M16
G00X70685Y595787
G40
M15
G01X74985
M16
G00X70685Y422559
G40
M15
G01X74985
M16
G00X70685Y190275
G40
M15
G01X74985
M16
G00X70685Y17047
G40
M15
G01X74985
M16
G40
M30
